# SCM (Grand Teton) — schematic netlist excerpt (pin names and nets, part order shuffled) for the footprints in the layout excerpt that follows; sources: Cadence DE-HDL packaged netlist, KiCad conversion of 12092022_DA0F0TMDCD0_F0T_Management_Board_D_brd_V3_OCP.brd

DB4  TDR_3P  EMPTY  pkg TH2  page 60
  GND  = T_GND
  IO1  = TDR_SE_50_OHM_IN3
  IO2  = TDR_SE_50_OHM_IN3

R261  Q_RES  10K 1% CHIP  pkg 0402LF  page 27 : A = P3V3_AUX ; B = SMB_BMC_MM9_SDA
R518  Q_RES  33.2 1% CHIP  pkg 0402LF  page 32 : A = JTAG_SCM_PLD_R1_JTAGEN ; B = JTAG_SCM_PLD_JTAGEN

(kicad_pcb
	(version 20260206)
	(generator "pcbnew")
	(generator_version "10.0")
	(general
		(thickness 1.6)
		(legacy_teardrops no)
	)
	(paper "A4")
	(title_block
		(title "12092022_DA0F0TMDCD0_F0T_Management_Board_D_brd_V3_OCP.brd")
		(comment 1 "Grand Teton / footprints 600-602 of 1440")
	)
	(layers
		(0 "F.Cu" signal "TOP")
		(4 "In1.Cu" signal "GND")
		(6 "In2.Cu" signal "IN1")
		(8 "In3.Cu" signal "GND1")
		(10 "In4.Cu" signal "IN2")
		(12 "In5.Cu" signal "VCC")
		(14 "In6.Cu" signal "VCC1")
		(16 "In7.Cu" signal "IN3")
		(18 "In8.Cu" signal "GND2")
		(20 "In9.Cu" signal "IN4")
		(22 "In10.Cu" signal "GND3")
		(2 "B.Cu" signal "BOTTOM")
		(9 "F.Adhes" user "F.Adhesive")
		(11 "B.Adhes" user "B.Adhesive")
		(13 "F.Paste" user "Package Geometry/Pastemask Top")
		(15 "B.Paste" user "Package Geometry/Pastemask Bottom")
		(5 "F.SilkS" user "Ref Des/Silkscreen Top")
		(7 "B.SilkS" user "Ref Des/Silkscreen Bottom")
		(1 "F.Mask" user "Board Geometry/Soldermask Top")
		(3 "B.Mask" user "Board Geometry/Soldermask Bottom")
		(17 "Dwgs.User" user "User.Drawings")
		(19 "Cmts.User" user "User.Comments")
		(21 "Eco1.User" user "User.Eco1")
		(23 "Eco2.User" user "User.Eco2")
		(25 "Edge.Cuts" user "Board Geometry/Outline")
		(27 "Margin" user)
		(31 "F.CrtYd" user "Package Geometry/Place Bound Top")
		(29 "B.CrtYd" user "Package Geometry/Place Bound Bottom")
		(35 "F.Fab" user "Ref Des/Assembly Top")
		(33 "B.Fab" user "Ref Des/Assembly Bottom")
	)
	(footprint ""
		(layer "F.Cu")
		(at -7.6454 -66.929 180)
		(property "Reference" "DB4"
			(at -1.0668 -5.826252 0)
			(unlocked yes)
			(layer "F.SilkS")
			(effects
				(font
					(size 0.7874 0.5842)
					(thickness 0.1524)
				)
				(justify left)
			)
		)
		(property "Value" ""
			(at 0 0 180)
			(layer "F.Fab")
			(effects
				(font
					(size 1.27 1.27)
				)
			)
		)
		(duplicate_pad_numbers_are_jumpers no)
		(fp_line
			(start 3.330702 -4.771136)
			(end 0 4.011168)
			(stroke
				(width 0.1524)
				(type default)
			)
			(layer "F.SilkS")
		)
		(fp_line
			(start 0 4.011168)
			(end -3.330702 -4.771136)
			(stroke
				(width 0.1524)
				(type default)
			)
			(layer "F.SilkS")
		)
		(fp_line
			(start -3.330702 -4.771136)
			(end 3.330702 -4.771136)
			(stroke
				(width 0.1524)
				(type default)
			)
			(layer "F.SilkS")
		)
		(fp_line
			(start 3.330702 -4.771136)
			(end 0 4.011168)
			(stroke
				(width 0.1)
				(type default)
			)
			(layer "F.Fab")
		)
		(fp_line
			(start 0 4.011168)
			(end -3.330702 -4.771136)
			(stroke
				(width 0.1)
				(type default)
			)
			(layer "F.Fab")
		)
		(fp_line
			(start -3.330702 -4.771136)
			(end 3.330702 -4.771136)
			(stroke
				(width 0.1)
				(type default)
			)
			(layer "F.Fab")
		)
		(pad "1" thru_hole circle
			(at 0 0 180)
			(size 2.159 2.159)
			(drill 1.7018)
			(layers "*.Cu" "*.Mask")
			(remove_unused_layers no)
			(net "T_GND")
			(clearance 0.0254)
			(thermal_gap 0.0254)
		)
		(pad "2" thru_hole circle
			(at -1.27 -3.348736 180)
			(size 2.159 2.159)
			(drill 1.7018)
			(layers "*.Cu" "*.Mask")
			(remove_unused_layers no)
			(net "TDR_SE_50_OHM_IN3")
			(clearance 0.0254)
			(thermal_gap 0.0254)
		)
		(pad "3" thru_hole circle
			(at 1.27 -3.348736 180)
			(size 2.159 2.159)
			(drill 1.7018)
			(layers "*.Cu" "*.Mask")
			(remove_unused_layers no)
			(net "TDR_SE_50_OHM_IN3")
			(clearance 0.0254)
			(thermal_gap 0.0254)
		)
	)
	(footprint ""
		(layer "F.Cu")
		(at 53.388006 -30.867604 90)
		(property "Reference" "R261"
			(at 0 0 90)
			(layer "F.SilkS")
			(hide yes)
			(effects
				(font
					(size 1.27 1.27)
				)
			)
		)
		(property "Value" ""
			(at 0 0 90)
			(layer "F.Fab")
			(effects
				(font
					(size 1.27 1.27)
				)
			)
		)
		(duplicate_pad_numbers_are_jumpers no)
		(fp_line
			(start 0.7874 -0.4064)
			(end 0.7874 0.4064)
			(stroke
				(width 0.1524)
				(type default)
			)
			(layer "F.SilkS")
		)
		(fp_line
			(start -0.7874 -0.4064)
			(end 0.7874 -0.4064)
			(stroke
				(width 0.1524)
				(type default)
			)
			(layer "F.SilkS")
		)
		(fp_line
			(start 0.7874 0.4064)
			(end -0.7874 0.4064)
			(stroke
				(width 0.1524)
				(type default)
			)
			(layer "F.SilkS")
		)
		(fp_line
			(start -0.7874 0.4064)
			(end -0.7874 -0.4064)
			(stroke
				(width 0.1524)
				(type default)
			)
			(layer "F.SilkS")
		)
		(fp_line
			(start -0.12065 -0.305054)
			(end -0.12065 -0.2794)
			(stroke
				(width 0.1)
				(type default)
			)
			(layer "F.Fab")
		)
		(fp_line
			(start -0.67945 -0.305054)
			(end -0.12065 -0.305054)
			(stroke
				(width 0.1)
				(type default)
			)
			(layer "F.Fab")
		)
		(fp_line
			(start 0.67945 -0.3048)
			(end 0.67945 0.3048)
			(stroke
				(width 0.1)
				(type default)
			)
			(layer "F.Fab")
		)
		(fp_line
			(start 0.12065 -0.3048)
			(end 0.67945 -0.3048)
			(stroke
				(width 0.1)
				(type default)
			)
			(layer "F.Fab")
		)
		(fp_line
			(start 0.12065 -0.2794)
			(end 0.12065 -0.3048)
			(stroke
				(width 0.1)
				(type default)
			)
			(layer "F.Fab")
		)
		(fp_line
			(start -0.12065 -0.2794)
			(end 0.12065 -0.2794)
			(stroke
				(width 0.1)
				(type default)
			)
			(layer "F.Fab")
		)
		(fp_line
			(start 0.120396 0.2794)
			(end -0.12065 0.2794)
			(stroke
				(width 0.1)
				(type default)
			)
			(layer "F.Fab")
		)
		(fp_line
			(start -0.12065 0.2794)
			(end -0.12065 0.3048)
			(stroke
				(width 0.1)
				(type default)
			)
			(layer "F.Fab")
		)
		(fp_line
			(start 0.67945 0.3048)
			(end 0.120396 0.3048)
			(stroke
				(width 0.1)
				(type default)
			)
			(layer "F.Fab")
		)
		(fp_line
			(start 0.120396 0.3048)
			(end 0.120396 0.2794)
			(stroke
				(width 0.1)
				(type default)
			)
			(layer "F.Fab")
		)
		(fp_line
			(start -0.12065 0.3048)
			(end -0.67945 0.3048)
			(stroke
				(width 0.1)
				(type default)
			)
			(layer "F.Fab")
		)
		(fp_line
			(start -0.67945 0.3048)
			(end -0.67945 -0.305054)
			(stroke
				(width 0.1)
				(type default)
			)
			(layer "F.Fab")
		)
		(pad "1" smd circle
			(at -0.40005 0 90)
			(size 0 0)
			(layers "F.Cu" "F.Mask" "F.Paste")
			(net "P3V3_AUX")
		)
		(pad "2" smd circle
			(at 0.40005 0 90)
			(size 0 0)
			(layers "F.Cu" "F.Mask" "F.Paste")
			(net "SMB_BMC_MM9_SDA")
		)
	)
	(footprint ""
		(layer "F.Cu")
		(at 10.287 -98.298 -90)
		(property "Reference" "R518"
			(at 0 0 270)
			(layer "F.SilkS")
			(hide yes)
			(effects
				(font
					(size 1.27 1.27)
				)
			)
		)
		(property "Value" ""
			(at 0 0 270)
			(layer "F.Fab")
			(effects
				(font
					(size 1.27 1.27)
				)
			)
		)
		(duplicate_pad_numbers_are_jumpers no)
		(fp_line
			(start -0.7874 0.4064)
			(end -0.7874 -0.4064)
			(stroke
				(width 0.1524)
				(type default)
			)
			(layer "F.SilkS")
		)
		(fp_line
			(start 0.7874 0.4064)
			(end -0.7874 0.4064)
			(stroke
				(width 0.1524)
				(type default)
			)
			(layer "F.SilkS")
		)
		(fp_line
			(start -0.7874 -0.4064)
			(end 0.7874 -0.4064)
			(stroke
				(width 0.1524)
				(type default)
			)
			(layer "F.SilkS")
		)
		(fp_line
			(start 0.7874 -0.4064)
			(end 0.7874 0.4064)
			(stroke
				(width 0.1524)
				(type default)
			)
			(layer "F.SilkS")
		)
		(fp_line
			(start -0.67945 0.3048)
			(end -0.67945 -0.305054)
			(stroke
				(width 0.1)
				(type default)
			)
			(layer "F.Fab")
		)
		(fp_line
			(start -0.12065 0.3048)
			(end -0.67945 0.3048)
			(stroke
				(width 0.1)
				(type default)
			)
			(layer "F.Fab")
		)
		(fp_line
			(start 0.120396 0.3048)
			(end 0.120396 0.2794)
			(stroke
				(width 0.1)
				(type default)
			)
			(layer "F.Fab")
		)
		(fp_line
			(start 0.67945 0.3048)
			(end 0.120396 0.3048)
			(stroke
				(width 0.1)
				(type default)
			)
			(layer "F.Fab")
		)
		(fp_line
			(start -0.12065 0.2794)
			(end -0.12065 0.3048)
			(stroke
				(width 0.1)
				(type default)
			)
			(layer "F.Fab")
		)
		(fp_line
			(start 0.120396 0.2794)
			(end -0.12065 0.2794)
			(stroke
				(width 0.1)
				(type default)
			)
			(layer "F.Fab")
		)
		(fp_line
			(start -0.12065 -0.2794)
			(end 0.12065 -0.2794)
			(stroke
				(width 0.1)
				(type default)
			)
			(layer "F.Fab")
		)
		(fp_line
			(start 0.12065 -0.2794)
			(end 0.12065 -0.3048)
			(stroke
				(width 0.1)
				(type default)
			)
			(layer "F.Fab")
		)
		(fp_line
			(start 0.12065 -0.3048)
			(end 0.67945 -0.3048)
			(stroke
				(width 0.1)
				(type default)
			)
			(layer "F.Fab")
		)
		(fp_line
			(start 0.67945 -0.3048)
			(end 0.67945 0.3048)
			(stroke
				(width 0.1)
				(type default)
			)
			(layer "F.Fab")
		)
		(fp_line
			(start -0.67945 -0.305054)
			(end -0.12065 -0.305054)
			(stroke
				(width 0.1)
				(type default)
			)
			(layer "F.Fab")
		)
		(fp_line
			(start -0.12065 -0.305054)
			(end -0.12065 -0.2794)
			(stroke
				(width 0.1)
				(type default)
			)
			(layer "F.Fab")
		)
		(pad "1" smd circle
			(at -0.40005 0 270)
			(size 0 0)
			(layers "F.Cu" "F.Mask" "F.Paste")
			(net "JTAG_SCM_PLD_R1_JTAGEN")
		)
		(pad "2" smd circle
			(at 0.40005 0 270)
			(size 0 0)
			(layers "F.Cu" "F.Mask" "F.Paste")
			(net "JTAG_SCM_PLD_JTAGEN")
		)
	)
)
